# SCM (Grand Teton) — schematic netlist excerpt (pin names and nets, part order shuffled) for the footprints in the layout excerpt that follows; sources: Cadence DE-HDL packaged netlist, KiCad conversion of 12092022_DA0F0TMDCD0_F0T_Management_Board_D_brd_V3_OCP.brd

R484  Q_RES  33.2 1% CHIP  pkg 0402LF  page 45 : A = SPI_PCH_MUXED_IO1 ; B = SPI_PCH_IO1_FLASH_R1
R404  Q_RES  10K 1% CHIP  pkg 0402LF  page 21 : A = P3V3_AUX ; B = BSM_PRSNT_N

(kicad_pcb
	(version 20260206)
	(generator "pcbnew")
	(generator_version "10.0")
	(general
		(thickness 1.6)
		(legacy_teardrops no)
	)
	(paper "A4")
	(title_block
		(title "12092022_DA0F0TMDCD0_F0T_Management_Board_D_brd_V3_OCP.brd")
		(comment 1 "Grand Teton / footprints 531-532 of 1440")
	)
	(layers
		(0 "F.Cu" signal "TOP")
		(4 "In1.Cu" signal "GND")
		(6 "In2.Cu" signal "IN1")
		(8 "In3.Cu" signal "GND1")
		(10 "In4.Cu" signal "IN2")
		(12 "In5.Cu" signal "VCC")
		(14 "In6.Cu" signal "VCC1")
		(16 "In7.Cu" signal "IN3")
		(18 "In8.Cu" signal "GND2")
		(20 "In9.Cu" signal "IN4")
		(22 "In10.Cu" signal "GND3")
		(2 "B.Cu" signal "BOTTOM")
		(9 "F.Adhes" user "F.Adhesive")
		(11 "B.Adhes" user "B.Adhesive")
		(13 "F.Paste" user "Package Geometry/Pastemask Top")
		(15 "B.Paste" user "Package Geometry/Pastemask Bottom")
		(5 "F.SilkS" user "Ref Des/Silkscreen Top")
		(7 "B.SilkS" user "Ref Des/Silkscreen Bottom")
		(1 "F.Mask" user "Board Geometry/Soldermask Top")
		(3 "B.Mask" user "Board Geometry/Soldermask Bottom")
		(17 "Dwgs.User" user "User.Drawings")
		(19 "Cmts.User" user "User.Comments")
		(21 "Eco1.User" user "User.Eco1")
		(23 "Eco2.User" user "User.Eco2")
		(25 "Edge.Cuts" user "Board Geometry/Outline")
		(27 "Margin" user)
		(31 "F.CrtYd" user "Package Geometry/Place Bound Top")
		(29 "B.CrtYd" user "Package Geometry/Place Bound Bottom")
		(35 "F.Fab" user "Ref Des/Assembly Top")
		(33 "B.Fab" user "Ref Des/Assembly Bottom")
	)
	(footprint ""
		(layer "F.Cu")
		(at 43.948604 -87.679784 90)
		(property "Reference" "R484"
			(at 0 0 90)
			(layer "F.SilkS")
			(hide yes)
			(effects
				(font
					(size 1.27 1.27)
				)
			)
		)
		(property "Value" ""
			(at 0 0 90)
			(layer "F.Fab")
			(effects
				(font
					(size 1.27 1.27)
				)
			)
		)
		(duplicate_pad_numbers_are_jumpers no)
		(fp_line
			(start 0.7874 -0.4064)
			(end 0.7874 0.4064)
			(stroke
				(width 0.1524)
				(type default)
			)
			(layer "F.SilkS")
		)
		(fp_line
			(start -0.7874 -0.4064)
			(end 0.7874 -0.4064)
			(stroke
				(width 0.1524)
				(type default)
			)
			(layer "F.SilkS")
		)
		(fp_line
			(start 0.7874 0.4064)
			(end -0.7874 0.4064)
			(stroke
				(width 0.1524)
				(type default)
			)
			(layer "F.SilkS")
		)
		(fp_line
			(start -0.7874 0.4064)
			(end -0.7874 -0.4064)
			(stroke
				(width 0.1524)
				(type default)
			)
			(layer "F.SilkS")
		)
		(fp_line
			(start -0.12065 -0.305054)
			(end -0.12065 -0.2794)
			(stroke
				(width 0.1)
				(type default)
			)
			(layer "F.Fab")
		)
		(fp_line
			(start -0.67945 -0.305054)
			(end -0.12065 -0.305054)
			(stroke
				(width 0.1)
				(type default)
			)
			(layer "F.Fab")
		)
		(fp_line
			(start 0.67945 -0.3048)
			(end 0.67945 0.3048)
			(stroke
				(width 0.1)
				(type default)
			)
			(layer "F.Fab")
		)
		(fp_line
			(start 0.12065 -0.3048)
			(end 0.67945 -0.3048)
			(stroke
				(width 0.1)
				(type default)
			)
			(layer "F.Fab")
		)
		(fp_line
			(start 0.12065 -0.2794)
			(end 0.12065 -0.3048)
			(stroke
				(width 0.1)
				(type default)
			)
			(layer "F.Fab")
		)
		(fp_line
			(start -0.12065 -0.2794)
			(end 0.12065 -0.2794)
			(stroke
				(width 0.1)
				(type default)
			)
			(layer "F.Fab")
		)
		(fp_line
			(start 0.120396 0.2794)
			(end -0.12065 0.2794)
			(stroke
				(width 0.1)
				(type default)
			)
			(layer "F.Fab")
		)
		(fp_line
			(start -0.12065 0.2794)
			(end -0.12065 0.3048)
			(stroke
				(width 0.1)
				(type default)
			)
			(layer "F.Fab")
		)
		(fp_line
			(start 0.67945 0.3048)
			(end 0.120396 0.3048)
			(stroke
				(width 0.1)
				(type default)
			)
			(layer "F.Fab")
		)
		(fp_line
			(start 0.120396 0.3048)
			(end 0.120396 0.2794)
			(stroke
				(width 0.1)
				(type default)
			)
			(layer "F.Fab")
		)
		(fp_line
			(start -0.12065 0.3048)
			(end -0.67945 0.3048)
			(stroke
				(width 0.1)
				(type default)
			)
			(layer "F.Fab")
		)
		(fp_line
			(start -0.67945 0.3048)
			(end -0.67945 -0.305054)
			(stroke
				(width 0.1)
				(type default)
			)
			(layer "F.Fab")
		)
		(pad "1" smd circle
			(at -0.40005 0 90)
			(size 0 0)
			(layers "F.Cu" "F.Mask" "F.Paste")
			(net "SPI_PCH_MUXED_IO1")
		)
		(pad "2" smd circle
			(at 0.40005 0 90)
			(size 0 0)
			(layers "F.Cu" "F.Mask" "F.Paste")
			(net "SPI_PCH_IO1_FLASH_R1")
		)
	)
	(footprint ""
		(layer "F.Cu")
		(at 24.257 -68.834 90)
		(property "Reference" "R404"
			(at 0 0 90)
			(layer "F.SilkS")
			(hide yes)
			(effects
				(font
					(size 1.27 1.27)
				)
			)
		)
		(property "Value" ""
			(at 0 0 90)
			(layer "F.Fab")
			(effects
				(font
					(size 1.27 1.27)
				)
			)
		)
		(duplicate_pad_numbers_are_jumpers no)
		(fp_line
			(start 0.7874 -0.4064)
			(end 0.7874 0.4064)
			(stroke
				(width 0.1524)
				(type default)
			)
			(layer "F.SilkS")
		)
		(fp_line
			(start -0.7874 -0.4064)
			(end 0.7874 -0.4064)
			(stroke
				(width 0.1524)
				(type default)
			)
			(layer "F.SilkS")
		)
		(fp_line
			(start 0.7874 0.4064)
			(end -0.7874 0.4064)
			(stroke
				(width 0.1524)
				(type default)
			)
			(layer "F.SilkS")
		)
		(fp_line
			(start -0.7874 0.4064)
			(end -0.7874 -0.4064)
			(stroke
				(width 0.1524)
				(type default)
			)
			(layer "F.SilkS")
		)
		(fp_line
			(start -0.12065 -0.305054)
			(end -0.12065 -0.2794)
			(stroke
				(width 0.1)
				(type default)
			)
			(layer "F.Fab")
		)
		(fp_line
			(start -0.67945 -0.305054)
			(end -0.12065 -0.305054)
			(stroke
				(width 0.1)
				(type default)
			)
			(layer "F.Fab")
		)
		(fp_line
			(start 0.67945 -0.3048)
			(end 0.67945 0.3048)
			(stroke
				(width 0.1)
				(type default)
			)
			(layer "F.Fab")
		)
		(fp_line
			(start 0.12065 -0.3048)
			(end 0.67945 -0.3048)
			(stroke
				(width 0.1)
				(type default)
			)
			(layer "F.Fab")
		)
		(fp_line
			(start 0.12065 -0.2794)
			(end 0.12065 -0.3048)
			(stroke
				(width 0.1)
				(type default)
			)
			(layer "F.Fab")
		)
		(fp_line
			(start -0.12065 -0.2794)
			(end 0.12065 -0.2794)
			(stroke
				(width 0.1)
				(type default)
			)
			(layer "F.Fab")
		)
		(fp_line
			(start 0.120396 0.2794)
			(end -0.12065 0.2794)
			(stroke
				(width 0.1)
				(type default)
			)
			(layer "F.Fab")
		)
		(fp_line
			(start -0.12065 0.2794)
			(end -0.12065 0.3048)
			(stroke
				(width 0.1)
				(type default)
			)
			(layer "F.Fab")
		)
		(fp_line
			(start 0.67945 0.3048)
			(end 0.120396 0.3048)
			(stroke
				(width 0.1)
				(type default)
			)
			(layer "F.Fab")
		)
		(fp_line
			(start 0.120396 0.3048)
			(end 0.120396 0.2794)
			(stroke
				(width 0.1)
				(type default)
			)
			(layer "F.Fab")
		)
		(fp_line
			(start -0.12065 0.3048)
			(end -0.67945 0.3048)
			(stroke
				(width 0.1)
				(type default)
			)
			(layer "F.Fab")
		)
		(fp_line
			(start -0.67945 0.3048)
			(end -0.67945 -0.305054)
			(stroke
				(width 0.1)
				(type default)
			)
			(layer "F.Fab")
		)
		(pad "1" smd circle
			(at -0.40005 0 90)
			(size 0 0)
			(layers "F.Cu" "F.Mask" "F.Paste")
			(net "P3V3_AUX")
		)
		(pad "2" smd circle
			(at 0.40005 0 90)
			(size 0 0)
			(layers "F.Cu" "F.Mask" "F.Paste")
			(net "BSM_PRSNT_N")
		)
	)
)
